(kicad_pcb
	(version 20260206)
	(generator "pcbnew")
	(generator_version "10.0")
	(general
		(thickness 1.6)
		(legacy_teardrops no)
	)
	(paper "A4")
	(title_block
		(title "pdpb — Lightning_PDPB_BRD.brd")
		(comment 1 "Lightning (Wiwynn / Facebook NVMe JBOF) / footprints 745-751 of 1140")
	)
	(layers
		(0 "F.Cu" signal "TOP")
		(4 "In1.Cu" signal "L2GND")
		(6 "In2.Cu" signal "L3")
		(8 "In3.Cu" signal "L4VCC")
		(10 "In4.Cu" signal "L5VCC")
		(12 "In5.Cu" signal "L6")
		(14 "In6.Cu" signal "L7GND")
		(2 "B.Cu" signal "BOTTOM")
		(9 "F.Adhes" user "F.Adhesive")
		(11 "B.Adhes" user "B.Adhesive")
		(13 "F.Paste" user "Package Geometry/Pastemask Top")
		(15 "B.Paste" user "Package Geometry/Pastemask Bottom")
		(5 "F.SilkS" user "Ref Des/Silkscreen Top")
		(7 "B.SilkS" user "Ref Des/Silkscreen Bottom")
		(1 "F.Mask" user "Board Geometry/Soldermask Top")
		(3 "B.Mask" user "Board Geometry/Soldermask Bottom")
		(17 "Dwgs.User" user "User.Drawings")
		(19 "Cmts.User" user "User.Comments")
		(21 "Eco1.User" user "User.Eco1")
		(23 "Eco2.User" user "User.Eco2")
		(25 "Edge.Cuts" user "Board Geometry/Outline")
		(27 "Margin" user)
		(31 "F.CrtYd" user "Package Geometry/Place Bound Top")
		(29 "B.CrtYd" user "Package Geometry/Place Bound Bottom")
		(35 "F.Fab" user "Ref Des/Assembly Top")
		(33 "B.Fab" user "Ref Des/Assembly Bottom")
	)
	(footprint ""
		(layer "F.Cu")
		(at 95.0722 -21.9456)
		(property "Reference" "C359"
			(at 0 0 0)
			(layer "F.SilkS")
			(hide yes)
			(effects
				(font
					(size 1.27 1.27)
				)
			)
		)
		(property "Value" "SCD1U16V2KX-3GP"
			(at 1.1811 -2.7051 0)
			(unlocked yes)
			(layer "F.Fab")
			(hide yes)
			(effects
				(font
					(size 1.016 1.016)
					(thickness 0.1524)
				)
			)
		)
		(property "Device Type" "C402H22"
			(at 1.1811 -4.2291 0)
			(unlocked yes)
			(layer "F.Fab")
			(hide yes)
			(effects
				(font
					(size 1.016 1.016)
					(thickness 0.1524)
				)
			)
		)
		(duplicate_pad_numbers_are_jumpers no)
		(fp_rect
			(start -0.4318 0.9525)
			(end 0.4318 -0.9525)
			(stroke
				(width 0)
				(type default)
			)
			(fill no)
			(layer "F.CrtYd")
		)
		(fp_rect
			(start -0.4318 0.9525)
			(end 0.4318 -0.9525)
			(stroke
				(width 0)
				(type default)
			)
			(fill no)
			(layer "F.Fab")
		)
		(pad "1" smd custom
			(at 0 -0.4445)
			(size 0.1524 0.1524)
			(layers "F.Cu" "F.Mask" "F.Paste")
			(net "P12V_SSD14_SENSE")
			(options
				(clearance outline)
				(anchor circle)
			)
			(primitives
				(gr_poly
					(pts
						(arc
							(start 0.3048 -0.2032)
							(mid 0.275042 -0.275042)
							(end 0.2032 -0.3048)
						)
						(arc
							(start -0.2032 -0.3048)
							(mid -0.275042 -0.275042)
							(end -0.3048 -0.2032)
						)
						(arc
							(start -0.3048 0.2032)
							(mid -0.275042 0.275042)
							(end -0.2032 0.3048)
						)
						(arc
							(start 0.2032 0.3048)
							(mid 0.275042 0.275042)
							(end 0.3048 0.2032)
						)
					)
					(width 0)
					(fill yes)
				)
			)
		)
		(pad "2" smd custom
			(at 0 0.4445)
			(size 0.1524 0.1524)
			(layers "F.Cu" "F.Mask" "F.Paste")
			(net "GND")
			(options
				(clearance outline)
				(anchor circle)
			)
			(primitives
				(gr_poly
					(pts
						(arc
							(start 0.3048 -0.2032)
							(mid 0.275042 -0.275042)
							(end 0.2032 -0.3048)
						)
						(arc
							(start -0.2032 -0.3048)
							(mid -0.275042 -0.275042)
							(end -0.3048 -0.2032)
						)
						(arc
							(start -0.3048 0.2032)
							(mid -0.275042 0.275042)
							(end -0.2032 0.3048)
						)
						(arc
							(start 0.2032 0.3048)
							(mid 0.275042 0.275042)
							(end 0.3048 0.2032)
						)
					)
					(width 0)
					(fill yes)
				)
			)
		)
	)
	(footprint ""
		(layer "F.Cu")
		(at 70.000114 -173.99762)
		(property "Reference" "H7"
			(at 0 0 0)
			(layer "F.SilkS")
			(hide yes)
			(effects
				(font
					(size 1.27 1.27)
				)
			)
		)
		(property "Value" "GEN276X162R197X296-6-F-A-GP"
			(at -6.7183 4.1402 0)
			(unlocked yes)
			(layer "F.Fab")
			(hide yes)
			(effects
				(font
					(size 1.016 1.016)
					(thickness 0.1524)
				)
			)
		)
		(property "Device Type" "GEN276X162R197X296-6-F-A"
			(at -6.7183 2.6162 0)
			(unlocked yes)
			(layer "F.Fab")
			(hide yes)
			(effects
				(font
					(size 1.016 1.016)
					(thickness 0.1524)
				)
			)
		)
		(duplicate_pad_numbers_are_jumpers no)
		(fp_poly
			(pts
				(arc
					(start 2.723642 4.777232)
					(mid -0.000169 6.508462)
					(end -2.723896 4.776978)
				)
				(arc
					(start -2.723896 4.776978)
					(mid 0.000173 -5.499012)
					(end 2.723642 4.777232)
				)
			)
			(stroke
				(width 0)
				(type default)
			)
			(fill no)
			(layer "B.CrtYd")
		)
		(fp_poly
			(pts
				(arc
					(start 2.723642 4.777232)
					(mid -0.000169 6.508462)
					(end -2.723896 4.776978)
				)
				(arc
					(start -2.723896 4.776978)
					(mid 0.000173 -5.499012)
					(end 2.723642 4.777232)
				)
			)
			(stroke
				(width 0)
				(type default)
			)
			(fill no)
			(layer "F.CrtYd")
		)
		(fp_poly
			(pts
				(arc
					(start 2.723642 4.777232)
					(mid -0.000169 6.508462)
					(end -2.723896 4.776978)
				)
				(arc
					(start -2.723896 4.776978)
					(mid 0.000173 -5.499012)
					(end 2.723642 4.777232)
				)
			)
			(stroke
				(width 0)
				(type default)
			)
			(fill no)
			(layer "B.Fab")
		)
		(fp_poly
			(pts
				(arc
					(start 2.723642 4.777232)
					(mid -0.000169 6.508462)
					(end -2.723896 4.776978)
				)
				(arc
					(start -2.723896 4.776978)
					(mid 0.000173 -5.499012)
					(end 2.723642 4.777232)
				)
			)
			(stroke
				(width 0)
				(type default)
			)
			(fill no)
			(layer "F.Fab")
		)
		(pad "" np_thru_hole circle
			(at 0 0)
			(size 0.254 0.254)
			(drill 0.0254)
			(layers "*.Cu" "*.Mask")
			(clearance 3.135376)
			(thermal_gap 3.135376)
		)
		(pad "1" thru_hole circle
			(at 2.549906 0)
			(size 0.8636 0.8636)
			(drill 0.508)
			(layers "*.Cu" "*.Mask")
			(remove_unused_layers no)
			(net "GND")
			(clearance 0.8255)
			(thermal_gap 0.8255)
		)
		(pad "2" thru_hole circle
			(at 2.210054 -1.27)
			(size 0.8636 0.8636)
			(drill 0.508)
			(layers "*.Cu" "*.Mask")
			(remove_unused_layers no)
			(net "GND")
			(clearance 0.8255)
			(thermal_gap 0.8255)
		)
		(pad "3" thru_hole circle
			(at 1.27 -2.210054)
			(size 0.8636 0.8636)
			(drill 0.508)
			(layers "*.Cu" "*.Mask")
			(remove_unused_layers no)
			(net "GND")
			(clearance 0.8255)
			(thermal_gap 0.8255)
		)
		(pad "4" thru_hole circle
			(at -1.279906 -2.210054)
			(size 0.8636 0.8636)
			(drill 0.508)
			(layers "*.Cu" "*.Mask")
			(remove_unused_layers no)
			(net "GND")
			(clearance 0.8255)
			(thermal_gap 0.8255)
		)
		(pad "5" thru_hole circle
			(at -2.210054 -1.27)
			(size 0.8636 0.8636)
			(drill 0.508)
			(layers "*.Cu" "*.Mask")
			(remove_unused_layers no)
			(net "GND")
			(clearance 0.8255)
			(thermal_gap 0.8255)
		)
		(pad "6" thru_hole circle
			(at -2.549906 0)
			(size 0.8636 0.8636)
			(drill 0.508)
			(layers "*.Cu" "*.Mask")
			(remove_unused_layers no)
			(net "GND")
			(clearance 0.8255)
			(thermal_gap 0.8255)
		)
		(zone
			(layers "F.Cu" "B.Cu" "In1.Cu" "In2.Cu" "In3.Cu" "In4.Cu" "In5.Cu" "In6.Cu")
			(hatch none 0.5)
			(connect_pads
				(clearance 0)
			)
			(min_thickness 0.25)
			(keepout
				(tracks allowed)
				(vias not_allowed)
				(pads allowed)
				(copperpour not_allowed)
				(footprints allowed)
			)
			(placement
				(enabled no)
				(sheetname "")
			)
			(fill
				(thermal_gap 0.5)
				(thermal_bridge_width 0.5)
				(island_removal_mode 0)
			)
			(polygon
				(pts
					(arc
						(start 74.318114 -174.000668)
						(mid 65.682114 -174.000668)
						(end 74.318114 -174.000668)
					)
				)
			)
		)
		(zone
			(layers "F.Cu" "B.Cu" "In1.Cu" "In2.Cu" "In3.Cu" "In4.Cu" "In5.Cu" "In6.Cu")
			(hatch none 0.5)
			(connect_pads
				(clearance 0)
			)
			(min_thickness 0.25)
			(keepout
				(tracks not_allowed)
				(vias allowed)
				(pads allowed)
				(copperpour not_allowed)
				(footprints allowed)
			)
			(placement
				(enabled no)
				(sheetname "")
			)
			(fill
				(thermal_gap 0.5)
				(thermal_bridge_width 0.5)
				(island_removal_mode 0)
			)
			(polygon
				(pts
					(arc
						(start 72.339454 -172.388276)
						(mid 70.000194 -167.489173)
						(end 67.66052 -172.388276)
					)
					(arc
						(start 67.66052 -172.388276)
						(mid 67.906487 -172.828642)
						(end 67.991736 -173.32579)
					)
					(arc
						(start 67.991736 -173.99762)
						(mid 70.000114 -176.005998)
						(end 72.008238 -173.99762)
					)
					(arc
						(start 72.008238 -173.32579)
						(mid 72.093473 -172.828636)
						(end 72.339454 -172.388276)
					)
				)
			)
		)
	)
	(footprint ""
		(layer "F.Cu")
		(at 40.5638 -313.4614 180)
		(property "Reference" "D29"
			(at 0 0 180)
			(layer "F.SilkS")
			(hide yes)
			(effects
				(font
					(size 1.27 1.27)
				)
			)
		)
		(property "Value" "RB551V30-1-GP"
			(at 0 -6.7818 180)
			(unlocked yes)
			(layer "F.Fab")
			(hide yes)
			(effects
				(font
					(size 1.016 1.016)
					(thickness 0.1524)
				)
			)
		)
		(property "Device Type" "SOD323AKH44"
			(at 0 -8.6868 180)
			(unlocked yes)
			(layer "F.Fab")
			(hide yes)
			(effects
				(font
					(size 1.016 1.016)
					(thickness 0.1524)
				)
			)
		)
		(duplicate_pad_numbers_are_jumpers no)
		(fp_line
			(start 0.889 2.159)
			(end -0.889 2.159)
			(stroke
				(width 0.1524)
				(type default)
			)
			(layer "F.SilkS")
		)
		(fp_line
			(start 0.889 -1.9304)
			(end 0.889 2.159)
			(stroke
				(width 0.1524)
				(type default)
			)
			(layer "F.SilkS")
		)
		(fp_line
			(start 0.762 2.0574)
			(end -0.762 2.0574)
			(stroke
				(width 0.508)
				(type default)
			)
			(layer "F.SilkS")
		)
		(fp_line
			(start -0.889 2.159)
			(end -0.889 -1.9304)
			(stroke
				(width 0.1524)
				(type default)
			)
			(layer "F.SilkS")
		)
		(fp_line
			(start -0.889 -1.9304)
			(end 0.889 -1.9304)
			(stroke
				(width 0.1524)
				(type default)
			)
			(layer "F.SilkS")
		)
		(fp_rect
			(start -1.016 2.3114)
			(end 1.016 -2.0066)
			(stroke
				(width 0)
				(type default)
			)
			(fill no)
			(layer "F.CrtYd")
		)
		(fp_poly
			(pts
				(xy -1.016 -2.0066) (xy 1.016 -2.0066) (xy 1.016 2.3114) (xy -1.016 2.3114)
			)
			(stroke
				(width 0)
				(type default)
			)
			(fill no)
			(layer "F.Fab")
		)
		(pad "A" smd rect
			(at 0 -1.143 180)
			(size 0.5588 1.016)
			(layers "F.Cu" "F.Mask" "F.Paste")
			(net "SW_SSD11_R")
		)
		(pad "K" smd rect
			(at 0 1.143 180)
			(size 0.5588 1.016)
			(layers "F.Cu" "F.Mask" "F.Paste")
			(net "SW_SSD11_N")
		)
	)
	(footprint ""
		(layer "F.Cu")
		(at 32.004 -374.65 180)
		(property "Reference" "R331"
			(at 0 0 180)
			(layer "F.SilkS")
			(hide yes)
			(effects
				(font
					(size 1.27 1.27)
				)
			)
		)
		(property "Value" "4K7R2F-GP"
			(at 0.064008 -3.993896 180)
			(unlocked yes)
			(layer "F.Fab")
			(hide yes)
			(effects
				(font
					(size 1.016 1.016)
					(thickness 0.1524)
				)
			)
		)
		(property "Device Type" "R402H16"
			(at 0.064008 -5.517896 180)
			(unlocked yes)
			(layer "F.Fab")
			(hide yes)
			(effects
				(font
					(size 1.016 1.016)
					(thickness 0.1524)
				)
			)
		)
		(duplicate_pad_numbers_are_jumpers no)
		(fp_line
			(start 0.508 -0.9398)
			(end -0.508 -0.9398)
			(stroke
				(width 0.1524)
				(type default)
			)
			(layer "F.SilkS")
		)
		(fp_line
			(start -0.508 -0.9398)
			(end -0.508 0.9398)
			(stroke
				(width 0.1524)
				(type default)
			)
			(layer "F.SilkS")
		)
		(fp_rect
			(start -0.508 0.9398)
			(end 0.508 -0.9398)
			(stroke
				(width 0)
				(type default)
			)
			(fill no)
			(layer "F.CrtYd")
		)
		(fp_rect
			(start -0.508 0.9398)
			(end 0.508 -0.9398)
			(stroke
				(width 0)
				(type default)
			)
			(fill no)
			(layer "F.Fab")
		)
		(pad "1" smd custom
			(at 0 -0.4445 180)
			(size 0.1397 0.1397)
			(layers "F.Cu" "F.Mask" "F.Paste")
			(net "P3V3")
			(options
				(clearance outline)
				(anchor circle)
			)
			(primitives
				(gr_poly
					(pts
						(arc
							(start -0.1778 -0.2794)
							(mid -0.249642 -0.249642)
							(end -0.2794 -0.1778)
						)
						(arc
							(start -0.2794 0.1778)
							(mid -0.249642 0.249642)
							(end -0.1778 0.2794)
						)
						(arc
							(start 0.1778 0.2794)
							(mid 0.249642 0.249642)
							(end 0.2794 0.1778)
						)
						(arc
							(start 0.2794 -0.1778)
							(mid 0.249642 -0.249642)
							(end 0.1778 -0.2794)
						)
					)
					(width 0)
					(fill yes)
				)
			)
		)
		(pad "2" smd custom
			(at 0 0.4445 180)
			(size 0.1397 0.1397)
			(layers "F.Cu" "F.Mask" "F.Paste")
			(net "I2C_B_TMP4_A2")
			(options
				(clearance outline)
				(anchor circle)
			)
			(primitives
				(gr_poly
					(pts
						(arc
							(start -0.1778 -0.2794)
							(mid -0.249642 -0.249642)
							(end -0.2794 -0.1778)
						)
						(arc
							(start -0.2794 0.1778)
							(mid -0.249642 0.249642)
							(end -0.1778 0.2794)
						)
						(arc
							(start 0.1778 0.2794)
							(mid 0.249642 0.249642)
							(end 0.2794 0.1778)
						)
						(arc
							(start 0.2794 -0.1778)
							(mid 0.249642 -0.249642)
							(end 0.1778 -0.2794)
						)
					)
					(width 0)
					(fill yes)
				)
			)
		)
	)
	(footprint ""
		(layer "F.Cu")
		(at 222.0468 -85.979)
		(property "Reference" "PC1203"
			(at 0 0 0)
			(layer "F.SilkS")
			(hide yes)
			(effects
				(font
					(size 1.27 1.27)
				)
			)
		)
		(property "Value" "SCD01U50V2KX-1GP"
			(at 1.1811 -2.7051 0)
			(unlocked yes)
			(layer "F.Fab")
			(hide yes)
			(effects
				(font
					(size 1.016 1.016)
					(thickness 0.1524)
				)
			)
		)
		(property "Device Type" "C402H22"
			(at 1.1811 -4.2291 0)
			(unlocked yes)
			(layer "F.Fab")
			(hide yes)
			(effects
				(font
					(size 1.016 1.016)
					(thickness 0.1524)
				)
			)
		)
		(duplicate_pad_numbers_are_jumpers no)
		(fp_rect
			(start -0.4318 0.9525)
			(end 0.4318 -0.9525)
			(stroke
				(width 0)
				(type default)
			)
			(fill no)
			(layer "F.CrtYd")
		)
		(fp_rect
			(start -0.4318 0.9525)
			(end 0.4318 -0.9525)
			(stroke
				(width 0)
				(type default)
			)
			(fill no)
			(layer "F.Fab")
		)
		(pad "1" smd custom
			(at 0 -0.4445)
			(size 0.1524 0.1524)
			(layers "F.Cu" "F.Mask" "F.Paste")
			(net "P12V_SSD4")
			(options
				(clearance outline)
				(anchor circle)
			)
			(primitives
				(gr_poly
					(pts
						(arc
							(start 0.3048 -0.2032)
							(mid 0.275042 -0.275042)
							(end 0.2032 -0.3048)
						)
						(arc
							(start -0.2032 -0.3048)
							(mid -0.275042 -0.275042)
							(end -0.3048 -0.2032)
						)
						(arc
							(start -0.3048 0.2032)
							(mid -0.275042 0.275042)
							(end -0.2032 0.3048)
						)
						(arc
							(start 0.2032 0.3048)
							(mid 0.275042 0.275042)
							(end 0.3048 0.2032)
						)
					)
					(width 0)
					(fill yes)
				)
			)
		)
		(pad "2" smd custom
			(at 0 0.4445)
			(size 0.1524 0.1524)
			(layers "F.Cu" "F.Mask" "F.Paste")
			(net "GND")
			(options
				(clearance outline)
				(anchor circle)
			)
			(primitives
				(gr_poly
					(pts
						(arc
							(start 0.3048 -0.2032)
							(mid 0.275042 -0.275042)
							(end 0.2032 -0.3048)
						)
						(arc
							(start -0.2032 -0.3048)
							(mid -0.275042 -0.275042)
							(end -0.3048 -0.2032)
						)
						(arc
							(start -0.3048 0.2032)
							(mid -0.275042 0.275042)
							(end -0.2032 0.3048)
						)
						(arc
							(start 0.2032 0.3048)
							(mid 0.275042 0.275042)
							(end 0.3048 0.2032)
						)
					)
					(width 0)
					(fill yes)
				)
			)
		)
	)
	(footprint ""
		(layer "F.Cu")
		(at 33.1089 -308.4449)
		(property "Reference" "R9852"
			(at 0 0 0)
			(layer "F.SilkS")
			(hide yes)
			(effects
				(font
					(size 1.27 1.27)
				)
			)
		)
		(property "Value" "47KR2J-2-GP"
			(at 0.064008 -3.993896 0)
			(unlocked yes)
			(layer "F.Fab")
			(hide yes)
			(effects
				(font
					(size 1.016 1.016)
					(thickness 0.1524)
				)
			)
		)
		(property "Device Type" "R402H16"
			(at 0.064008 -5.517896 0)
			(unlocked yes)
			(layer "F.Fab")
			(hide yes)
			(effects
				(font
					(size 1.016 1.016)
					(thickness 0.1524)
				)
			)
		)
		(duplicate_pad_numbers_are_jumpers no)
		(fp_line
			(start -0.508 -0.9398)
			(end -0.508 0.9398)
			(stroke
				(width 0.1524)
				(type default)
			)
			(layer "F.SilkS")
		)
		(fp_line
			(start 0.508 -0.9398)
			(end -0.508 -0.9398)
			(stroke
				(width 0.1524)
				(type default)
			)
			(layer "F.SilkS")
		)
		(fp_rect
			(start -0.508 0.9398)
			(end 0.508 -0.9398)
			(stroke
				(width 0)
				(type default)
			)
			(fill no)
			(layer "F.CrtYd")
		)
		(fp_rect
			(start -0.508 0.9398)
			(end 0.508 -0.9398)
			(stroke
				(width 0)
				(type default)
			)
			(fill no)
			(layer "F.Fab")
		)
		(pad "1" smd custom
			(at 0 -0.4445)
			(size 0.1397 0.1397)
			(layers "F.Cu" "F.Mask" "F.Paste")
			(net "P12V")
			(options
				(clearance outline)
				(anchor circle)
			)
			(primitives
				(gr_poly
					(pts
						(arc
							(start -0.1778 -0.2794)
							(mid -0.249642 -0.249642)
							(end -0.2794 -0.1778)
						)
						(arc
							(start -0.2794 0.1778)
							(mid -0.249642 0.249642)
							(end -0.1778 0.2794)
						)
						(arc
							(start 0.1778 0.2794)
							(mid 0.249642 0.249642)
							(end 0.2794 0.1778)
						)
						(arc
							(start 0.2794 -0.1778)
							(mid 0.249642 -0.249642)
							(end 0.1778 -0.2794)
						)
					)
					(width 0)
					(fill yes)
				)
			)
		)
		(pad "2" smd custom
			(at 0 0.4445)
			(size 0.1397 0.1397)
			(layers "F.Cu" "F.Mask" "F.Paste")
			(net "P12V_MOST11_GATE")
			(options
				(clearance outline)
				(anchor circle)
			)
			(primitives
				(gr_poly
					(pts
						(arc
							(start -0.1778 -0.2794)
							(mid -0.249642 -0.249642)
							(end -0.2794 -0.1778)
						)
						(arc
							(start -0.2794 0.1778)
							(mid -0.249642 0.249642)
							(end -0.1778 0.2794)
						)
						(arc
							(start 0.1778 0.2794)
							(mid 0.249642 0.249642)
							(end 0.2794 0.1778)
						)
						(arc
							(start 0.2794 -0.1778)
							(mid 0.249642 -0.249642)
							(end 0.1778 -0.2794)
						)
					)
					(width 0)
					(fill yes)
				)
			)
		)
	)
	(footprint ""
		(layer "F.Cu")
		(at 209.296 -87.122 180)
		(property "Reference" "R570"
			(at 0 0 180)
			(layer "F.SilkS")
			(hide yes)
			(effects
				(font
					(size 1.27 1.27)
				)
			)
		)
		(property "Value" "300KR2F-GP"
			(at 0.064008 -3.993896 180)
			(unlocked yes)
			(layer "F.Fab")
			(hide yes)
			(effects
				(font
					(size 1.016 1.016)
					(thickness 0.1524)
				)
			)
		)
		(property "Device Type" "R402H16"
			(at 0.064008 -5.517896 180)
			(unlocked yes)
			(layer "F.Fab")
			(hide yes)
			(effects
				(font
					(size 1.016 1.016)
					(thickness 0.1524)
				)
			)
		)
		(duplicate_pad_numbers_are_jumpers no)
		(fp_line
			(start 0.508 -0.9398)
			(end -0.508 -0.9398)
			(stroke
				(width 0.1524)
				(type default)
			)
			(layer "F.SilkS")
		)
		(fp_line
			(start -0.508 -0.9398)
			(end -0.508 0.9398)
			(stroke
				(width 0.1524)
				(type default)
			)
			(layer "F.SilkS")
		)
		(fp_rect
			(start -0.508 0.9398)
			(end 0.508 -0.9398)
			(stroke
				(width 0)
				(type default)
			)
			(fill no)
			(layer "F.CrtYd")
		)
		(fp_rect
			(start -0.508 0.9398)
			(end 0.508 -0.9398)
			(stroke
				(width 0)
				(type default)
			)
			(fill no)
			(layer "F.Fab")
		)
		(pad "1" smd custom
			(at 0 -0.4445 180)
			(size 0.1397 0.1397)
			(layers "F.Cu" "F.Mask" "F.Paste")
			(net "SW_SSD4_N")
			(options
				(clearance outline)
				(anchor circle)
			)
			(primitives
				(gr_poly
					(pts
						(arc
							(start -0.1778 -0.2794)
							(mid -0.249642 -0.249642)
							(end -0.2794 -0.1778)
						)
						(arc
							(start -0.2794 0.1778)
							(mid -0.249642 0.249642)
							(end -0.1778 0.2794)
						)
						(arc
							(start 0.1778 0.2794)
							(mid 0.249642 0.249642)
							(end 0.2794 0.1778)
						)
						(arc
							(start 0.2794 -0.1778)
							(mid 0.249642 -0.249642)
							(end 0.1778 -0.2794)
						)
					)
					(width 0)
					(fill yes)
				)
			)
		)
		(pad "2" smd custom
			(at 0 0.4445 180)
			(size 0.1397 0.1397)
			(layers "F.Cu" "F.Mask" "F.Paste")
			(net "P12V")
			(options
				(clearance outline)
				(anchor circle)
			)
			(primitives
				(gr_poly
					(pts
						(arc
							(start -0.1778 -0.2794)
							(mid -0.249642 -0.249642)
							(end -0.2794 -0.1778)
						)
						(arc
							(start -0.2794 0.1778)
							(mid -0.249642 0.249642)
							(end -0.1778 0.2794)
						)
						(arc
							(start 0.1778 0.2794)
							(mid 0.249642 0.249642)
							(end 0.2794 0.1778)
						)
						(arc
							(start 0.2794 -0.1778)
							(mid 0.249642 -0.249642)
							(end 0.1778 -0.2794)
						)
					)
					(width 0)
					(fill yes)
				)
			)
		)
	)
)
